# T6G (Grand Teton) — schematic netlist excerpt (pin names and nets, part order shuffled) for the footprints in the layout excerpt that follows; sources: Cadence DE-HDL packaged netlist, KiCad conversion of 04192023_DAF0TMB3IC0_F0TG_MB_C_brd_V02_OCP.brd

PC495  Q_CAPP  220UF 4V 20% SPCAP  pkg SMLF  page 194 : A = PVDDCR_CPU0_P0 ; B = GND
C1886  Q_CAP  0.1UF 25V 10% X7R  pkg 0402  page 233 : A = VFG3P3_CLK_GEN ; B = GND

(kicad_pcb
	(version 20260206)
	(generator "pcbnew")
	(generator_version "10.0")
	(general
		(thickness 1.6)
		(legacy_teardrops no)
	)
	(paper "A4")
	(title_block
		(title "04192023_DAF0TMB3IC0_F0TG_MB_C_brd_V02_OCP.brd")
		(comment 1 "Grand Teton / footprints 6242-6243 of 8354")
	)
	(layers
		(0 "F.Cu" signal "TOP")
		(4 "In1.Cu" signal "GND")
		(6 "In2.Cu" signal "IN1")
		(8 "In3.Cu" signal "GND1")
		(10 "In4.Cu" signal "IN2")
		(12 "In5.Cu" signal "GND2")
		(14 "In6.Cu" signal "IN3")
		(16 "In7.Cu" signal "GND3")
		(18 "In8.Cu" signal "VCC")
		(20 "In9.Cu" signal "VCC1")
		(22 "In10.Cu" signal "GND4")
		(24 "In11.Cu" signal "IN4")
		(26 "In12.Cu" signal "GND5")
		(28 "In13.Cu" signal "IN5")
		(30 "In14.Cu" signal "GND6")
		(32 "In15.Cu" signal "IN6")
		(34 "In16.Cu" signal "GND7")
		(2 "B.Cu" signal "BOTTOM")
		(9 "F.Adhes" user "F.Adhesive")
		(11 "B.Adhes" user "B.Adhesive")
		(13 "F.Paste" user "Package Geometry/Pastemask Top")
		(15 "B.Paste" user "Package Geometry/Pastemask Bottom")
		(5 "F.SilkS" user "Ref Des/Silkscreen Top")
		(7 "B.SilkS" user "Ref Des/Silkscreen Bottom")
		(1 "F.Mask" user "Board Geometry/Soldermask Top")
		(3 "B.Mask" user "Board Geometry/Soldermask Bottom")
		(17 "Dwgs.User" user "User.Drawings")
		(19 "Cmts.User" user "User.Comments")
		(21 "Eco1.User" user "User.Eco1")
		(23 "Eco2.User" user "User.Eco2")
		(25 "Edge.Cuts" user "Board Geometry/Outline")
		(27 "Margin" user)
		(31 "F.CrtYd" user "Package Geometry/Place Bound Top")
		(29 "B.CrtYd" user "Package Geometry/Place Bound Bottom")
		(35 "F.Fab" user "Ref Des/Assembly Top")
		(33 "B.Fab" user "Ref Des/Assembly Bottom")
	)
	(footprint ""
		(layer "B.Cu")
		(at 355.927406 -176.244504 90)
		(property "Reference" "PC495"
			(at 6.798056 -0.502666 270)
			(unlocked yes)
			(layer "B.SilkS")
			(effects
				(font
					(size 0.7874 0.5842)
					(thickness 0.1524)
				)
				(justify left mirror)
			)
		)
		(property "Value" ""
			(at 0 0 90)
			(layer "B.Fab")
			(effects
				(font
					(size 1.27 1.27)
				)
				(justify mirror)
			)
		)
		(duplicate_pad_numbers_are_jumpers no)
		(fp_line
			(start 4.533392 -2.249932)
			(end -4.533392 -2.249932)
			(stroke
				(width 0.1524)
				(type default)
			)
			(layer "B.SilkS")
		)
		(fp_line
			(start -4.533392 -2.249932)
			(end -4.533392 2.249932)
			(stroke
				(width 0.1524)
				(type default)
			)
			(layer "B.SilkS")
		)
		(fp_line
			(start 4.533392 2.249932)
			(end 4.533392 -2.249932)
			(stroke
				(width 0.1524)
				(type default)
			)
			(layer "B.SilkS")
		)
		(fp_line
			(start -4.533392 2.249932)
			(end 4.533392 2.249932)
			(stroke
				(width 0.1524)
				(type default)
			)
			(layer "B.SilkS")
		)
		(fp_rect
			(start 4.533392 -2.326132)
			(end 5.39242 2.326132)
			(stroke
				(width 0)
				(type default)
			)
			(fill yes)
			(layer "B.SilkS")
		)
		(fp_line
			(start 3.750056 -2.249932)
			(end -3.750056 -2.249932)
			(stroke
				(width 0.1)
				(type default)
			)
			(layer "B.Fab")
		)
		(fp_line
			(start -3.750056 -2.249932)
			(end -3.750056 2.249932)
			(stroke
				(width 0.1)
				(type default)
			)
			(layer "B.Fab")
		)
		(fp_line
			(start 3.750056 2.249932)
			(end 3.750056 -2.249932)
			(stroke
				(width 0.1)
				(type default)
			)
			(layer "B.Fab")
		)
		(fp_line
			(start -3.750056 2.249932)
			(end 3.750056 2.249932)
			(stroke
				(width 0.1)
				(type default)
			)
			(layer "B.Fab")
		)
		(fp_text user "-"
			(at -4.8514 -0.14605 90)
			(unlocked yes)
			(layer "B.SilkS")
			(effects
				(font
					(size 1.905 1.4224)
					(thickness 0.1524)
				)
				(justify left mirror)
			)
		)
		(fp_text user "+"
			(at 6.322314 0.786384 0)
			(unlocked yes)
			(layer "B.SilkS")
			(effects
				(font
					(size 1.905 1.4224)
					(thickness 0.1524)
				)
				(justify left mirror)
			)
		)
		(fp_text user "-"
			(at -4.8514 -0.14605 90)
			(unlocked yes)
			(layer "B.Fab")
			(effects
				(font
					(size 1.905 1.4224)
					(thickness 0.1524)
				)
				(justify left mirror)
			)
		)
		(fp_text user "+"
			(at 6.322314 0.786384 0)
			(unlocked yes)
			(layer "B.Fab")
			(effects
				(font
					(size 1.905 1.4224)
					(thickness 0.1524)
				)
				(justify left mirror)
			)
		)
		(pad "1" smd rect
			(at 3.199892 0 270)
			(size 2.413 2.8194)
			(layers "B.Cu" "B.Mask" "B.Paste")
			(net "PVDDCR_CPU0_P0")
		)
		(pad "2" smd rect
			(at -3.199892 0 270)
			(size 2.413 2.8194)
			(layers "B.Cu" "B.Mask" "B.Paste")
			(net "GND")
		)
	)
	(footprint ""
		(layer "B.Cu")
		(at 11.709908 -132.55625 -90)
		(property "Reference" "C1886"
			(at 0 0 90)
			(layer "B.SilkS")
			(hide yes)
			(effects
				(font
					(size 1.27 1.27)
				)
				(justify mirror)
			)
		)
		(property "Value" ""
			(at 0 0 90)
			(layer "B.Fab")
			(effects
				(font
					(size 1.27 1.27)
				)
				(justify mirror)
			)
		)
		(duplicate_pad_numbers_are_jumpers no)
		(fp_line
			(start -0.7874 0.4064)
			(end 0.7874 0.4064)
			(stroke
				(width 0.1524)
				(type default)
			)
			(layer "B.SilkS")
		)
		(fp_line
			(start 0.7874 0.4064)
			(end 0.7874 -0.4064)
			(stroke
				(width 0.1524)
				(type default)
			)
			(layer "B.SilkS")
		)
		(fp_line
			(start -0.7874 -0.4064)
			(end -0.7874 0.4064)
			(stroke
				(width 0.1524)
				(type default)
			)
			(layer "B.SilkS")
		)
		(fp_line
			(start 0.7874 -0.4064)
			(end -0.7874 -0.4064)
			(stroke
				(width 0.1524)
				(type default)
			)
			(layer "B.SilkS")
		)
		(fp_line
			(start -0.67945 0.3048)
			(end -0.120396 0.3048)
			(stroke
				(width 0.1)
				(type default)
			)
			(layer "B.Fab")
		)
		(fp_line
			(start -0.120396 0.3048)
			(end -0.120396 0.2794)
			(stroke
				(width 0.1)
				(type default)
			)
			(layer "B.Fab")
		)
		(fp_line
			(start 0.12065 0.3048)
			(end 0.67945 0.3048)
			(stroke
				(width 0.1)
				(type default)
			)
			(layer "B.Fab")
		)
		(fp_line
			(start 0.67945 0.3048)
			(end 0.67945 -0.305054)
			(stroke
				(width 0.1)
				(type default)
			)
			(layer "B.Fab")
		)
		(fp_line
			(start -0.120396 0.2794)
			(end 0.12065 0.2794)
			(stroke
				(width 0.1)
				(type default)
			)
			(layer "B.Fab")
		)
		(fp_line
			(start 0.12065 0.2794)
			(end 0.12065 0.3048)
			(stroke
				(width 0.1)
				(type default)
			)
			(layer "B.Fab")
		)
		(fp_line
			(start -0.12065 -0.2794)
			(end -0.12065 -0.3048)
			(stroke
				(width 0.1)
				(type default)
			)
			(layer "B.Fab")
		)
		(fp_line
			(start 0.12065 -0.2794)
			(end -0.12065 -0.2794)
			(stroke
				(width 0.1)
				(type default)
			)
			(layer "B.Fab")
		)
		(fp_line
			(start -0.67945 -0.3048)
			(end -0.67945 0.3048)
			(stroke
				(width 0.1)
				(type default)
			)
			(layer "B.Fab")
		)
		(fp_line
			(start -0.12065 -0.3048)
			(end -0.67945 -0.3048)
			(stroke
				(width 0.1)
				(type default)
			)
			(layer "B.Fab")
		)
		(fp_line
			(start 0.12065 -0.305054)
			(end 0.12065 -0.2794)
			(stroke
				(width 0.1)
				(type default)
			)
			(layer "B.Fab")
		)
		(fp_line
			(start 0.67945 -0.305054)
			(end 0.12065 -0.305054)
			(stroke
				(width 0.1)
				(type default)
			)
			(layer "B.Fab")
		)
		(pad "1" smd circle
			(at 0.40005 0 90)
			(size 0 0)
			(layers "B.Cu" "B.Mask" "B.Paste")
			(net "VFG3P3_CLK_GEN")
		)
		(pad "2" smd circle
			(at -0.40005 0 90)
			(size 0 0)
			(layers "B.Cu" "B.Mask" "B.Paste")
			(net "GND")
		)
	)
)
